(kicad_pcb
	(version 20241229)
	(generator "pcbnew")
	(generator_version "9.0")
	(general
		(thickness 1.6296)
		(legacy_teardrops no)
	)
	(paper "A3")
	(title_block
		(title "Thunderbolt to 10GbE adapter")
		(date "2026-04-21")
		(rev "1.1.0")
		(company "Antmicro Ltd")
		(comment 1 "www.antmicro.com")
		(comment 9 "footprints 511-515 of 703")
	)
	(layers
		(0 "F.Cu" signal)
		(4 "In1.Cu" signal)
		(6 "In2.Cu" signal)
		(8 "In3.Cu" signal)
		(10 "In4.Cu" signal)
		(12 "In5.Cu" signal)
		(14 "In6.Cu" signal)
		(2 "B.Cu" signal)
		(9 "F.Adhes" user "F.Adhesive")
		(11 "B.Adhes" user "B.Adhesive")
		(13 "F.Paste" user)
		(15 "B.Paste" user)
		(5 "F.SilkS" user "F.Silkscreen")
		(7 "B.SilkS" user "B.Silkscreen")
		(1 "F.Mask" user)
		(3 "B.Mask" user)
		(17 "Dwgs.User" user "User.Drawings")
		(19 "Cmts.User" user "User.Comments")
		(21 "Eco1.User" user "User.Eco1")
		(23 "Eco2.User" user "User.Eco2")
		(25 "Edge.Cuts" user)
		(27 "Margin" user)
		(31 "F.CrtYd" user "F.Courtyard")
		(29 "B.CrtYd" user "B.Courtyard")
		(35 "F.Fab" user)
		(33 "B.Fab" user)
	)
	(footprint "antmicro-footprints:R_0402_1005Metric"
		(layer "B.Cu")
		(at 144.181866 76.260117 -90)
		(descr "Resistor SMD 0402")
		(tags "resistor SMD 0402")
		(property "Reference" "R116"
			(at -0.010117 1.181866 90)
			(layer "B.SilkS")
			(effects
				(font
					(size 0.7 0.7)
					(thickness 0.15)
				)
				(justify mirror)
			)
		)
		(property "Value" "R_4k75_0.5%_0402"
			(at -1.011843 -1.772047 90)
			(layer "B.Fab")
			(effects
				(font
					(size 0.7 0.7)
					(thickness 0.15)
				)
				(justify left bottom mirror)
			)
		)
		(property "Datasheet" "https://industrial.panasonic.com/cdbs/www-data/pdf/RDQ0000/ast-ind-151033.pdf"
			(at 0 0 90)
			(layer "B.Fab")
			(hide yes)
			(effects
				(font
					(size 1.27 1.27)
					(thickness 0.15)
				)
				(justify mirror)
			)
		)
		(property "Description" "SMD Chip Resistor, 4.75 kohm, ± 0.5%, 100 mW, 0402 [1005 Metric], Thick Film, High Temperature"
			(at 0 0 90)
			(layer "B.Fab")
			(hide yes)
			(effects
				(font
					(size 1.27 1.27)
					(thickness 0.15)
				)
				(justify mirror)
			)
		)
		(property "MPN" "ERJ-H2RD4751X"
			(at 0 0 270)
			(unlocked yes)
			(layer "B.Fab")
			(hide yes)
			(effects
				(font
					(size 1 1)
					(thickness 0.15)
				)
				(justify mirror)
			)
		)
		(property "Manufacturer" "Panasonic"
			(at 0 0 270)
			(unlocked yes)
			(layer "B.Fab")
			(hide yes)
			(effects
				(font
					(size 1 1)
					(thickness 0.15)
				)
				(justify mirror)
			)
		)
		(property "License" "Apache-2.0"
			(at 0 0 270)
			(unlocked yes)
			(layer "B.Fab")
			(hide yes)
			(effects
				(font
					(size 1 1)
					(thickness 0.15)
				)
				(justify mirror)
			)
		)
		(property "Author" "Antmicro"
			(at 0 0 270)
			(unlocked yes)
			(layer "B.Fab")
			(hide yes)
			(effects
				(font
					(size 1 1)
					(thickness 0.15)
				)
				(justify mirror)
			)
		)
		(property "Val" "4k75"
			(at 0 0 270)
			(unlocked yes)
			(layer "B.Fab")
			(hide yes)
			(effects
				(font
					(size 1 1)
					(thickness 0.15)
				)
				(justify mirror)
			)
		)
		(property "Tolerance" "0.5%"
			(at 0 0 270)
			(unlocked yes)
			(layer "B.Fab")
			(hide yes)
			(effects
				(font
					(size 1 1)
					(thickness 0.15)
				)
				(justify mirror)
			)
		)
		(sheetname "/X710-AT2 PCIe/")
		(sheetfile "x710-at2-pcie.kicad_sch")
		(attr smd)
		(fp_rect
			(start -0.925 0.47)
			(end 0.925 -0.47)
			(stroke
				(width 0.05)
				(type default)
			)
			(fill no)
			(layer "B.CrtYd")
		)
		(fp_rect
			(start -0.5 0.25)
			(end 0.5 -0.25)
			(stroke
				(width 0.15)
				(type solid)
			)
			(fill no)
			(layer "B.Fab")
		)
		(fp_text user "License: Apache-2.0"
			(at -0.95 -5.169 90)
			(layer "B.Fab")
			(effects
				(font
					(size 0.7 0.7)
					(thickness 0.15)
				)
				(justify left bottom mirror)
			)
		)
		(fp_text user "Author: Antmicro"
			(at -0.95 -4.169 90)
			(layer "B.Fab")
			(effects
				(font
					(size 0.7 0.7)
					(thickness 0.15)
				)
				(justify left bottom mirror)
			)
		)
		(fp_text user "${REFERENCE}"
			(at -0.95 -3.168 90)
			(layer "B.Fab")
			(effects
				(font
					(size 0.7 0.7)
					(thickness 0.15)
				)
				(justify left bottom mirror)
			)
		)
		(pad "1" smd roundrect
			(at -0.48 0 270)
			(size 0.59 0.64)
			(layers "B.Cu" "B.Mask" "B.Paste")
			(roundrect_rratio 0.25)
			(net 3 "/X710-AT2 PCIe/RBIAS")
			(pintype "passive")
		)
		(pad "2" smd roundrect
			(at 0.48 0 270)
			(size 0.59 0.64)
			(layers "B.Cu" "B.Mask" "B.Paste")
			(roundrect_rratio 0.25)
			(net 2 "/X710-AT2 PCIe/RSENSE")
			(pintype "passive")
		)
	)
	(footprint "antmicro-footprints:R_0402_1005Metric"
		(layer "B.Cu")
		(at 152.580001 146.66 90)
		(descr "Resistor SMD 0402")
		(tags "resistor SMD 0402")
		(property "Reference" "R211"
			(at -1.09 0.42 270)
			(layer "B.SilkS")
			(effects
				(font
					(size 0.7 0.7)
					(thickness 0.15)
				)
				(justify left bottom mirror)
			)
		)
		(property "Value" "R_220R_0402"
			(at -1.011843 -1.772047 270)
			(layer "B.Fab")
			(effects
				(font
					(size 0.7 0.7)
					(thickness 0.15)
				)
				(justify left bottom mirror)
			)
		)
		(property "Datasheet" "https://www.bourns.com/docs/product-datasheets/cr.pdf"
			(at 0 0 270)
			(layer "B.Fab")
			(hide yes)
			(effects
				(font
					(size 1.27 1.27)
					(thickness 0.15)
				)
				(justify mirror)
			)
		)
		(property "Description" "SMD Chip Resistor, 220 ohm, ± 1%, 62.5 mW, 0402 [1005 Metric], Thick Film, General Purpose"
			(at 0 0 270)
			(layer "B.Fab")
			(hide yes)
			(effects
				(font
					(size 1.27 1.27)
					(thickness 0.15)
				)
				(justify mirror)
			)
		)
		(property "MPN" "CR0402-FX-2200GLF"
			(at 0 0 90)
			(unlocked yes)
			(layer "B.Fab")
			(hide yes)
			(effects
				(font
					(size 1 1)
					(thickness 0.15)
				)
				(justify mirror)
			)
		)
		(property "Manufacturer" "Bourns"
			(at 0 0 90)
			(unlocked yes)
			(layer "B.Fab")
			(hide yes)
			(effects
				(font
					(size 1 1)
					(thickness 0.15)
				)
				(justify mirror)
			)
		)
		(property "License" "Apache-2.0"
			(at 0 0 90)
			(unlocked yes)
			(layer "B.Fab")
			(hide yes)
			(effects
				(font
					(size 1 1)
					(thickness 0.15)
				)
				(justify mirror)
			)
		)
		(property "Author" "Antmicro"
			(at 0 0 90)
			(unlocked yes)
			(layer "B.Fab")
			(hide yes)
			(effects
				(font
					(size 1 1)
					(thickness 0.15)
				)
				(justify mirror)
			)
		)
		(property "Val" "220R"
			(at 0 0 90)
			(unlocked yes)
			(layer "B.Fab")
			(hide yes)
			(effects
				(font
					(size 1 1)
					(thickness 0.15)
				)
				(justify mirror)
			)
		)
		(property "Tolerance" "1%"
			(at 0 0 90)
			(unlocked yes)
			(layer "B.Fab")
			(hide yes)
			(effects
				(font
					(size 1 1)
					(thickness 0.15)
				)
				(justify mirror)
			)
		)
		(sheetname "/2xRJ45/")
		(sheetfile "2xrj45.kicad_sch")
		(attr smd)
		(fp_rect
			(start -0.925 0.47)
			(end 0.925 -0.47)
			(stroke
				(width 0.05)
				(type default)
			)
			(fill no)
			(layer "B.CrtYd")
		)
		(fp_rect
			(start -0.5 0.25)
			(end 0.5 -0.25)
			(stroke
				(width 0.15)
				(type solid)
			)
			(fill no)
			(layer "B.Fab")
		)
		(fp_text user "License: Apache-2.0"
			(at -0.95 -5.169 270)
			(layer "B.Fab")
			(effects
				(font
					(size 0.7 0.7)
					(thickness 0.15)
				)
				(justify left bottom mirror)
			)
		)
		(fp_text user "Author: Antmicro"
			(at -0.95 -4.169 270)
			(layer "B.Fab")
			(effects
				(font
					(size 0.7 0.7)
					(thickness 0.15)
				)
				(justify left bottom mirror)
			)
		)
		(fp_text user "${REFERENCE}"
			(at -0.95 -3.168 270)
			(layer "B.Fab")
			(effects
				(font
					(size 0.7 0.7)
					(thickness 0.15)
				)
				(justify left bottom mirror)
			)
		)
		(pad "1" smd roundrect
			(at -0.48 0 90)
			(size 0.59 0.64)
			(layers "B.Cu" "B.Mask" "B.Paste")
			(roundrect_rratio 0.25)
			(net 408 "Net-(J3-LED_YG_G-)")
			(pintype "passive")
		)
		(pad "2" smd roundrect
			(at 0.48 0 90)
			(size 0.59 0.64)
			(layers "B.Cu" "B.Mask" "B.Paste")
			(roundrect_rratio 0.25)
			(net 60 "/2xRJ45/~{P0_LED_LINK_10G}")
			(pintype "passive")
		)
	)
	(footprint "antmicro-footprints:R_0402_1005Metric"
		(layer "B.Cu")
		(at 136.5 118.175)
		(descr "Resistor SMD 0402")
		(tags "resistor SMD 0402")
		(property "Reference" "R43"
			(at 19.525001 -7.450001 180)
			(layer "B.SilkS")
			(effects
				(font
					(size 0.7 0.7)
					(thickness 0.15)
				)
				(justify mirror)
			)
		)
		(property "Value" "R_100k_0402"
			(at -1.011843 -1.772047 180)
			(layer "B.Fab")
			(effects
				(font
					(size 0.7 0.7)
					(thickness 0.15)
				)
				(justify left bottom mirror)
			)
		)
		(property "Datasheet" "https://www.bourns.com/docs/product-datasheets/cr.pdf"
			(at 0 0 180)
			(layer "B.Fab")
			(hide yes)
			(effects
				(font
					(size 1.27 1.27)
					(thickness 0.15)
				)
				(justify mirror)
			)
		)
		(property "Description" "SMD Chip Resistor, 100 kohm, ± 1%, 62.5 mW, 0402 [1005 Metric], Thick Film, General Purpose"
			(at 0 0 180)
			(layer "B.Fab")
			(hide yes)
			(effects
				(font
					(size 1.27 1.27)
					(thickness 0.15)
				)
				(justify mirror)
			)
		)
		(property "MPN" "CR0402-FX-1003GLF"
			(at 0 0 0)
			(unlocked yes)
			(layer "B.Fab")
			(hide yes)
			(effects
				(font
					(size 1 1)
					(thickness 0.15)
				)
				(justify mirror)
			)
		)
		(property "Manufacturer" "Bourns"
			(at 0 0 0)
			(unlocked yes)
			(layer "B.Fab")
			(hide yes)
			(effects
				(font
					(size 1 1)
					(thickness 0.15)
				)
				(justify mirror)
			)
		)
		(property "License" "Apache-2.0"
			(at 0 0 0)
			(unlocked yes)
			(layer "B.Fab")
			(hide yes)
			(effects
				(font
					(size 1 1)
					(thickness 0.15)
				)
				(justify mirror)
			)
		)
		(property "Val" "100k"
			(at 0 0 0)
			(unlocked yes)
			(layer "B.Fab")
			(hide yes)
			(effects
				(font
					(size 1 1)
					(thickness 0.15)
				)
				(justify mirror)
			)
		)
		(property "Tolerance" "1%"
			(at 0 0 0)
			(unlocked yes)
			(layer "B.Fab")
			(hide yes)
			(effects
				(font
					(size 1 1)
					(thickness 0.15)
				)
				(justify mirror)
			)
		)
		(property "Author" "Antmicro"
			(at 0 0 0)
			(unlocked yes)
			(layer "B.Fab")
			(hide yes)
			(effects
				(font
					(size 1 1)
					(thickness 0.15)
				)
				(justify mirror)
			)
		)
		(sheetname "/TB Controller/")
		(sheetfile "tb.kicad_sch")
		(attr smd)
		(fp_rect
			(start -0.925 0.47)
			(end 0.925 -0.47)
			(stroke
				(width 0.05)
				(type default)
			)
			(fill no)
			(layer "B.CrtYd")
		)
		(fp_rect
			(start -0.5 0.25)
			(end 0.5 -0.25)
			(stroke
				(width 0.15)
				(type solid)
			)
			(fill no)
			(layer "B.Fab")
		)
		(fp_text user "License: Apache-2.0"
			(at -0.95 -5.169 180)
			(layer "B.Fab")
			(effects
				(font
					(size 0.7 0.7)
					(thickness 0.15)
				)
				(justify left bottom mirror)
			)
		)
		(fp_text user "Author: Antmicro"
			(at -0.95 -4.169 180)
			(layer "B.Fab")
			(effects
				(font
					(size 0.7 0.7)
					(thickness 0.15)
				)
				(justify left bottom mirror)
			)
		)
		(fp_text user "${REFERENCE}"
			(at -0.95 -3.168 180)
			(layer "B.Fab")
			(effects
				(font
					(size 0.7 0.7)
					(thickness 0.15)
				)
				(justify left bottom mirror)
			)
		)
		(pad "1" smd roundrect
			(at -0.48 0)
			(size 0.59 0.64)
			(layers "B.Cu" "B.Mask" "B.Paste")
			(roundrect_rratio 0.25)
			(net 186 "Net-(U4C-GPIO_3)")
			(pintype "passive")
		)
		(pad "2" smd roundrect
			(at 0.48 0)
			(size 0.59 0.64)
			(layers "B.Cu" "B.Mask" "B.Paste")
			(roundrect_rratio 0.25)
			(net 23 "GND")
			(pintype "passive")
		)
	)
	(footprint "antmicro-footprints:R_0402_1005Metric"
		(layer "B.Cu")
		(at 148.681866 92.485117 90)
		(descr "Resistor SMD 0402")
		(tags "resistor SMD 0402")
		(property "Reference" "R142"
			(at -10.814884 18.718134 270)
			(layer "B.SilkS")
			(effects
				(font
					(size 0.7 0.7)
					(thickness 0.15)
				)
				(justify mirror)
			)
		)
		(property "Value" "R_0R_0402"
			(at -1.011843 -1.772047 270)
			(layer "B.Fab")
			(effects
				(font
					(size 0.7 0.7)
					(thickness 0.15)
				)
				(justify left bottom mirror)
			)
		)
		(property "Datasheet" "https://industrial.panasonic.com/cdbs/www-data/pdf/RDA0000/AOA0000C301.pdf"
			(at 0 0 270)
			(layer "B.Fab")
			(hide yes)
			(effects
				(font
					(size 1.27 1.27)
					(thickness 0.15)
				)
				(justify mirror)
			)
		)
		(property "Description" "SMD Chip Resistor, Jumper, 0 ohm, 100 mW, 0402 [1005 Metric], Thick Film, General Purpose"
			(at 0 0 270)
			(layer "B.Fab")
			(hide yes)
			(effects
				(font
					(size 1.27 1.27)
					(thickness 0.15)
				)
				(justify mirror)
			)
		)
		(property "MPN" "ERJ2GE0R00X"
			(at 0 0 90)
			(unlocked yes)
			(layer "B.Fab")
			(hide yes)
			(effects
				(font
					(size 1 1)
					(thickness 0.15)
				)
				(justify mirror)
			)
		)
		(property "Manufacturer" "Panasonic"
			(at 0 0 90)
			(unlocked yes)
			(layer "B.Fab")
			(hide yes)
			(effects
				(font
					(size 1 1)
					(thickness 0.15)
				)
				(justify mirror)
			)
		)
		(property "License" "Apache-2.0"
			(at 0 0 90)
			(unlocked yes)
			(layer "B.Fab")
			(hide yes)
			(effects
				(font
					(size 1 1)
					(thickness 0.15)
				)
				(justify mirror)
			)
		)
		(property "Author" "Antmicro"
			(at 0 0 90)
			(unlocked yes)
			(layer "B.Fab")
			(hide yes)
			(effects
				(font
					(size 1 1)
					(thickness 0.15)
				)
				(justify mirror)
			)
		)
		(property "Val" "0R"
			(at 0 0 90)
			(unlocked yes)
			(layer "B.Fab")
			(hide yes)
			(effects
				(font
					(size 1 1)
					(thickness 0.15)
				)
				(justify mirror)
			)
		)
		(property "Tolerance" "~"
			(at 0 0 90)
			(unlocked yes)
			(layer "B.Fab")
			(hide yes)
			(effects
				(font
					(size 1 1)
					(thickness 0.15)
				)
				(justify mirror)
			)
		)
		(property "Current" "1A"
			(at 0 0 90)
			(unlocked yes)
			(layer "B.Fab")
			(hide yes)
			(effects
				(font
					(size 1 1)
					(thickness 0.15)
				)
				(justify mirror)
			)
		)
		(sheetname "/X710-AT2 Misc/")
		(sheetfile "x710-at2-mics.kicad_sch")
		(attr smd)
		(fp_rect
			(start -0.925 0.47)
			(end 0.925 -0.47)
			(stroke
				(width 0.05)
				(type default)
			)
			(fill no)
			(layer "B.CrtYd")
		)
		(fp_rect
			(start -0.5 0.25)
			(end 0.5 -0.25)
			(stroke
				(width 0.15)
				(type solid)
			)
			(fill no)
			(layer "B.Fab")
		)
		(fp_text user "License: Apache-2.0"
			(at -0.95 -5.169 270)
			(layer "B.Fab")
			(effects
				(font
					(size 0.7 0.7)
					(thickness 0.15)
				)
				(justify left bottom mirror)
			)
		)
		(fp_text user "Author: Antmicro"
			(at -0.95 -4.169 270)
			(layer "B.Fab")
			(effects
				(font
					(size 0.7 0.7)
					(thickness 0.15)
				)
				(justify left bottom mirror)
			)
		)
		(fp_text user "${REFERENCE}"
			(at -0.95 -3.168 270)
			(layer "B.Fab")
			(effects
				(font
					(size 0.7 0.7)
					(thickness 0.15)
				)
				(justify left bottom mirror)
			)
		)
		(pad "1" smd roundrect
			(at -0.48 0 90)
			(size 0.59 0.64)
			(layers "B.Cu" "B.Mask" "B.Paste")
			(roundrect_rratio 0.25)
			(net 82 "/X710-AT2 Misc/GPIO5_POR_BYPASS")
			(pintype "passive")
		)
		(pad "2" smd roundrect
			(at 0.48 0 90)
			(size 0.59 0.64)
			(layers "B.Cu" "B.Mask" "B.Paste")
			(roundrect_rratio 0.25)
			(net 35 "/X710-AT2 Misc/POR_BYPASS")
			(pintype "passive")
		)
	)
	(footprint "antmicro-footprints:C_0402_1005Metric"
		(layer "B.Cu")
		(at 157.961866 84.055117 180)
		(descr "Capacitor SMD 0402")
		(tags "capacitor SMD 0402")
		(property "Reference" "C198"
			(at -20.793134 -9.464883 0)
			(layer "B.SilkS")
			(effects
				(font
					(size 0.7 0.7)
					(thickness 0.15)
				)
				(justify mirror)
			)
		)
		(property "Value" "C_1u_25V_0402"
			(at -1.022927 -2.155213 0)
			(layer "B.Fab")
			(effects
				(font
					(size 0.7 0.7)
					(thickness 0.15)
				)
				(justify left bottom mirror)
			)
		)
		(property "Datasheet" "https://www.murata.com/products/productdetail?partno=GRM155R61E105KE11%23"
			(at 0 0 0)
			(layer "B.Fab")
			(hide yes)
			(effects
				(font
					(size 1.27 1.27)
					(thickness 0.15)
				)
				(justify mirror)
			)
		)
		(property "Description" "SMD Multilayer Ceramic Capacitor, 1 µF, 25 V, 0402 [1005 Metric], ± 10%, X5R, GRM Series"
			(at 0 0 0)
			(layer "B.Fab")
			(hide yes)
			(effects
				(font
					(size 1.27 1.27)
					(thickness 0.15)
				)
				(justify mirror)
			)
		)
		(property "MPN" "GRM155R61E105KE11J"
			(at 0 0 180)
			(unlocked yes)
			(layer "B.Fab")
			(hide yes)
			(effects
				(font
					(size 1 1)
					(thickness 0.15)
				)
				(justify mirror)
			)
		)
		(property "Manufacturer" "Murata"
			(at 0 0 180)
			(unlocked yes)
			(layer "B.Fab")
			(hide yes)
			(effects
				(font
					(size 1 1)
					(thickness 0.15)
				)
				(justify mirror)
			)
		)
		(property "License" "Apache-2.0"
			(at 0 0 180)
			(unlocked yes)
			(layer "B.Fab")
			(hide yes)
			(effects
				(font
					(size 1 1)
					(thickness 0.15)
				)
				(justify mirror)
			)
		)
		(property "Author" "Antmicro"
			(at 0 0 180)
			(unlocked yes)
			(layer "B.Fab")
			(hide yes)
			(effects
				(font
					(size 1 1)
					(thickness 0.15)
				)
				(justify mirror)
			)
		)
		(property "Val" "1u"
			(at 0 0 180)
			(unlocked yes)
			(layer "B.Fab")
			(hide yes)
			(effects
				(font
					(size 1 1)
					(thickness 0.15)
				)
				(justify mirror)
			)
		)
		(property "Voltage" "25V"
			(at 0 0 180)
			(unlocked yes)
			(layer "B.Fab")
			(hide yes)
			(effects
				(font
					(size 1 1)
					(thickness 0.15)
				)
				(justify mirror)
			)
		)
		(property "Dielectric" "X5R"
			(at 0 0 180)
			(unlocked yes)
			(layer "B.Fab")
			(hide yes)
			(effects
				(font
					(size 1 1)
					(thickness 0.15)
				)
				(justify mirror)
			)
		)
		(sheetname "/X710-AT2 power/")
		(sheetfile "x710-at2-power.kicad_sch")
		(attr smd)
		(fp_rect
			(start -0.925 0.47)
			(end 0.925 -0.47)
			(stroke
				(width 0.05)
				(type default)
			)
			(fill no)
			(layer "B.CrtYd")
		)
		(fp_line
			(start 0.504 0.25)
			(end 0.504 -0.248)
			(stroke
				(width 0.15)
				(type solid)
			)
			(layer "B.Fab")
		)
		(fp_line
			(start 0.504 -0.248)
			(end -0.494 -0.248)
			(stroke
				(width 0.15)
				(type solid)
			)
			(layer "B.Fab")
		)
		(fp_line
			(start -0.494 0.25)
			(end 0.504 0.25)
			(stroke
				(width 0.15)
				(type solid)
			)
			(layer "B.Fab")
		)
		(fp_line
			(start -0.494 -0.248)
			(end -0.494 0.25)
			(stroke
				(width 0.15)
				(type solid)
			)
			(layer "B.Fab")
		)
		(fp_text user "Author: Antmicro"
			(at -0.939 -3.399 0)
			(layer "B.Fab")
			(effects
				(font
					(size 0.7 0.7)
					(thickness 0.15)
				)
				(justify left bottom mirror)
			)
		)
		(fp_text user "License: Apache-2.0"
			(at -0.939 -5.799 0)
			(layer "B.Fab")
			(effects
				(font
					(size 0.7 0.7)
					(thickness 0.15)
				)
				(justify left bottom mirror)
			)
		)
		(fp_text user "${REFERENCE}"
			(at -0.939 -4.599 0)
			(layer "B.Fab")
			(effects
				(font
					(size 0.7 0.7)
					(thickness 0.15)
				)
				(justify left bottom mirror)
			)
		)
		(pad "1" smd roundrect
			(at -0.48 0 180)
			(size 0.59 0.64)
			(layers "B.Cu" "B.Mask" "B.Paste")
			(roundrect_rratio 0.25)
			(net 23 "GND")
			(pintype "passive")
		)
		(pad "2" smd roundrect
			(at 0.48 0 180)
			(size 0.59 0.64)
			(layers "B.Cu" "B.Mask" "B.Paste")
			(roundrect_rratio 0.25)
			(net 10 "AVDDH")
			(pintype "passive")
		)
	)
)
